(kicad_sch
	(version 20250114)
	(generator "eeschema")
	(generator_version "9.0")
	(paper "A3")
	(title_block
		(title "OCuLink to PCIe adapter")
		(date "2025-06-18")
		(rev "1.0.0")
		(company "Antmicro Ltd")
		(comment 1 "www.antmicro.com")
	)
	(junction
		(at 224.79 147.32)
		(diameter 0)
		(color 0 0 0 0)
	)
	(junction
		(at 162.56 138.43)
		(diameter 0)
		(color 0 0 0 0)
	)
	(junction
		(at 162.56 151.13)
		(diameter 0)
		(color 0 0 0 0)
	)
	(junction
		(at 162.56 140.97)
		(diameter 0)
		(color 0 0 0 0)
	)
	(junction
		(at 153.67 138.43)
		(diameter 0)
		(color 0 0 0 0)
	)
	(junction
		(at 231.14 149.86)
		(diameter 0)
		(color 0 0 0 0)
	)
	(no_connect
		(at 190.5 142.24)
	)
	(no_connect
		(at 190.5 139.7)
	)
	(bus_entry
		(at 265.43 147.32)
		(size 1.27 -1.27)
		(stroke
			(width 0)
			(type default)
		)
	)
	(bus_entry
		(at 265.43 149.86)
		(size 1.27 -1.27)
		(stroke
			(width 0)
			(type default)
		)
	)
	(wire
		(pts
			(xy 219.71 149.86) (xy 231.14 149.86)
		)
		(stroke
			(width 0)
			(type default)
		)
	)
	(wire
		(pts
			(xy 162.56 138.43) (xy 163.83 138.43)
		)
		(stroke
			(width 0)
			(type default)
		)
	)
	(wire
		(pts
			(xy 153.67 138.43) (xy 153.67 139.7)
		)
		(stroke
			(width 0)
			(type default)
		)
	)
	(wire
		(pts
			(xy 162.56 144.78) (xy 162.56 140.97)
		)
		(stroke
			(width 0)
			(type default)
		)
	)
	(wire
		(pts
			(xy 162.56 151.13) (xy 163.83 151.13)
		)
		(stroke
			(width 0)
			(type default)
		)
	)
	(wire
		(pts
			(xy 231.14 149.86) (xy 243.84 149.86)
		)
		(stroke
			(width 0)
			(type default)
		)
	)
	(wire
		(pts
			(xy 153.67 138.43) (xy 162.56 138.43)
		)
		(stroke
			(width 0)
			(type default)
		)
	)
	(wire
		(pts
			(xy 190.5 147.32) (xy 214.63 147.32)
		)
		(stroke
			(width 0)
			(type default)
		)
	)
	(wire
		(pts
			(xy 162.56 148.59) (xy 162.56 151.13)
		)
		(stroke
			(width 0)
			(type default)
		)
	)
	(wire
		(pts
			(xy 162.56 140.97) (xy 162.56 138.43)
		)
		(stroke
			(width 0)
			(type default)
		)
	)
	(wire
		(pts
			(xy 231.14 161.29) (xy 231.14 160.02)
		)
		(stroke
			(width 0)
			(type default)
		)
	)
	(wire
		(pts
			(xy 224.79 147.32) (xy 243.84 147.32)
		)
		(stroke
			(width 0)
			(type default)
		)
	)
	(wire
		(pts
			(xy 224.79 147.32) (xy 224.79 154.94)
		)
		(stroke
			(width 0)
			(type default)
		)
	)
	(wire
		(pts
			(xy 190.5 149.86) (xy 214.63 149.86)
		)
		(stroke
			(width 0)
			(type default)
		)
	)
	(wire
		(pts
			(xy 163.83 140.97) (xy 162.56 140.97)
		)
		(stroke
			(width 0)
			(type default)
		)
	)
	(wire
		(pts
			(xy 231.14 149.86) (xy 231.14 154.94)
		)
		(stroke
			(width 0)
			(type default)
		)
	)
	(wire
		(pts
			(xy 224.79 161.29) (xy 224.79 160.02)
		)
		(stroke
			(width 0)
			(type default)
		)
	)
	(wire
		(pts
			(xy 153.67 138.43) (xy 153.67 137.16)
		)
		(stroke
			(width 0)
			(type default)
		)
	)
	(wire
		(pts
			(xy 163.83 144.78) (xy 162.56 144.78)
		)
		(stroke
			(width 0)
			(type default)
		)
	)
	(bus
		(pts
			(xy 266.7 148.59) (xy 266.7 146.05)
		)
		(stroke
			(width 0)
			(type default)
		)
	)
	(bus
		(pts
			(xy 266.7 143.51) (xy 267.97 142.24)
		)
		(stroke
			(width 0)
			(type default)
		)
	)
	(wire
		(pts
			(xy 163.83 148.59) (xy 162.56 148.59)
		)
		(stroke
			(width 0)
			(type default)
		)
	)
	(wire
		(pts
			(xy 248.92 149.86) (xy 265.43 149.86)
		)
		(stroke
			(width 0)
			(type default)
		)
	)
	(wire
		(pts
			(xy 219.71 147.32) (xy 224.79 147.32)
		)
		(stroke
			(width 0)
			(type default)
		)
	)
	(wire
		(pts
			(xy 248.92 147.32) (xy 265.43 147.32)
		)
		(stroke
			(width 0)
			(type default)
		)
	)
	(wire
		(pts
			(xy 162.56 152.4) (xy 162.56 151.13)
		)
		(stroke
			(width 0)
			(type default)
		)
	)
	(bus
		(pts
			(xy 266.7 146.05) (xy 266.7 143.51)
		)
		(stroke
			(width 0)
			(type default)
		)
	)
	(bus
		(pts
			(xy 267.97 142.24) (xy 270.51 142.24)
		)
		(stroke
			(width 0)
			(type default)
		)
	)
	(label "PCIe_{REF1}.CK-"
		(at 264.16 149.86 180)
		(effects
			(font
				(size 1.27 1.27)
			)
			(justify right bottom)
		)
	)
	(label "PCIe_{REF1}_R2.CK-"
		(at 209.55 149.86 180)
		(effects
			(font
				(size 1.27 1.27)
			)
			(justify right bottom)
		)
	)
	(label "PCIe_{REF1}.CK+"
		(at 264.16 147.32 180)
		(effects
			(font
				(size 1.27 1.27)
			)
			(justify right bottom)
		)
	)
	(label "PCIe_{REF1}_R2.CK+"
		(at 209.55 147.32 180)
		(effects
			(font
				(size 1.27 1.27)
			)
			(justify right bottom)
		)
	)
	(label "PCIe_{REF1}_R.CK+"
		(at 240.03 147.32 180)
		(effects
			(font
				(size 1.27 1.27)
			)
			(justify right bottom)
		)
	)
	(label "PCIe_{REF1}_R.CK-"
		(at 240.03 149.86 180)
		(effects
			(font
				(size 1.27 1.27)
			)
			(justify right bottom)
		)
	)
	(hierarchical_label "PCIe_{REF1}{PCIe_{REF}}"
		(shape output)
		(at 270.51 142.24 0)
		(effects
			(font
				(size 1.27 1.27)
			)
			(justify left)
		)
	)
	(rule_area
		(polyline
			(pts
				(xy 191.77 138.43) (xy 289.56 138.43) (xy 289.56 153.3525) (xy 191.77 153.3525)
			)
			(stroke
				(width 0)
				(type dash)
			)
			(fill
				(type none)
			)
		)
	)
	(netclass_flag ""
		(length 2.54)
		(shape round)
		(at 289.56 138.43 0)
		(effects
			(font
				(size 1.27 1.27)
				(color 0 132 0 1)
			)
			(justify left bottom)
		)
		(property "Netclass" "85Ohm-diff_PCIe"
			(at 289.56 134.112 0)
			(effects
				(font
					(size 1.27 1.27)
				)
			)
		)
		(property "Component Class" ""
			(at -82.55 22.86 0)
			(effects
				(font
					(size 1.27 1.27)
					(italic yes)
				)
			)
		)
	)
	(symbol
		(lib_id "antmicroResistors0402:R_0R_0402")
		(at 243.84 149.86 0)
		(unit 1)
		(exclude_from_sim no)
		(in_bom yes)
		(on_board yes)
		(dnp no)
		(property "Reference" "R44"
			(at 242.062 148.59 0)
			(effects
				(font
					(size 1.27 1.27)
					(thickness 0.15)
				)
			)
		)
		(property "Value" "R_0R_0402"
			(at 264.16 162.56 0)
			(effects
				(font
					(size 1.27 1.27)
					(thickness 0.15)
				)
				(justify left bottom)
				(hide yes)
			)
		)
		(property "Footprint" "antmicro-footprints:R_0402_1005Metric"
			(at 264.16 165.1 0)
			(effects
				(font
					(size 1.27 1.27)
					(thickness 0.15)
				)
				(justify left bottom)
				(hide yes)
			)
		)
		(property "Datasheet" "https://industrial.panasonic.com/cdbs/www-data/pdf/RDA0000/AOA0000C301.pdf"
			(at 264.16 167.64 0)
			(effects
				(font
					(size 1.27 1.27)
					(thickness 0.15)
				)
				(justify left bottom)
				(hide yes)
			)
		)
		(property "Description" "SMD Chip Resistor, Jumper, 0 ohm, 100 mW, 0402 [1005 Metric], Thick Film, General Purpose"
			(at 243.84 149.86 0)
			(effects
				(font
					(size 1.27 1.27)
				)
				(hide yes)
			)
		)
		(property "MPN" "ERJ2GE0R00X"
			(at 264.16 170.18 0)
			(effects
				(font
					(size 1.27 1.27)
					(thickness 0.15)
				)
				(justify left bottom)
				(hide yes)
			)
		)
		(property "Manufacturer" "Panasonic"
			(at 264.16 172.72 0)
			(effects
				(font
					(size 1.27 1.27)
					(thickness 0.15)
				)
				(justify left bottom)
				(hide yes)
			)
		)
		(property "License" "Apache-2.0"
			(at 264.16 175.26 0)
			(effects
				(font
					(size 1.27 1.27)
					(thickness 0.15)
				)
				(justify left bottom)
				(hide yes)
			)
		)
		(property "Author" "Antmicro"
			(at 264.16 177.8 0)
			(effects
				(font
					(size 1.27 1.27)
					(thickness 0.15)
				)
				(justify left bottom)
				(hide yes)
			)
		)
		(property "Val" "0R"
			(at 249.936 148.59 0)
			(effects
				(font
					(size 1.27 1.27)
					(thickness 0.15)
				)
			)
		)
		(property "Tolerance" "~"
			(at 264.16 160.02 0)
			(effects
				(font
					(size 1.27 1.27)
				)
				(justify left bottom)
				(hide yes)
			)
		)
		(property "Current" "1A"
			(at 264.16 180.34 0)
			(effects
				(font
					(size 1.27 1.27)
					(thickness 0.15)
				)
				(justify left bottom)
				(hide yes)
			)
		)
		(pin "1"
		)
		(pin "2"
		)
		(instances
			(project "oculink-to-pcie-adapter"
				(path ""
					(reference "R44")
					(unit 1)
				)
			)
		)
	)
	(symbol
		(lib_id "antmicropower:GND")
		(at 162.56 152.4 0)
		(unit 1)
		(exclude_from_sim no)
		(in_bom yes)
		(on_board yes)
		(dnp no)
		(property "Reference" "#PWR0104"
			(at 171.45 154.94 0)
			(effects
				(font
					(size 1.27 1.27)
					(thickness 0.15)
				)
				(justify left bottom)
				(hide yes)
			)
		)
		(property "Value" "GND"
			(at 162.56 156.21 0)
			(effects
				(font
					(size 1.27 1.27)
					(thickness 0.15)
				)
			)
		)
		(property "Footprint" ""
			(at 171.45 160.02 0)
			(effects
				(font
					(size 1.27 1.27)
					(thickness 0.15)
				)
				(justify left bottom)
				(hide yes)
			)
		)
		(property "Datasheet" ""
			(at 171.45 165.1 0)
			(effects
				(font
					(size 1.27 1.27)
					(thickness 0.15)
				)
				(justify left bottom)
				(hide yes)
			)
		)
		(property "Description" ""
			(at 162.56 152.4 0)
			(effects
				(font
					(size 1.27 1.27)
				)
				(hide yes)
			)
		)
		(property "Author" "Antmicro"
			(at 171.45 160.02 0)
			(effects
				(font
					(size 1.27 1.27)
					(thickness 0.15)
				)
				(justify left bottom)
				(hide yes)
			)
		)
		(property "License" "Apache-2.0"
			(at 171.45 162.56 0)
			(effects
				(font
					(size 1.27 1.27)
					(thickness 0.15)
				)
				(justify left bottom)
				(hide yes)
			)
		)
		(pin "1"
		)
		(instances
			(project "oculink-to-pcie-adapter"
				(path ""
					(reference "#PWR0104")
					(unit 1)
				)
			)
		)
	)
	(symbol
		(lib_id "antmicropower:+12V")
		(at 153.67 137.16 0)
		(unit 1)
		(exclude_from_sim no)
		(in_bom yes)
		(on_board yes)
		(dnp no)
		(property "Reference" "#PWR0348"
			(at 153.67 140.97 0)
			(effects
				(font
					(size 1.27 1.27)
				)
				(hide yes)
			)
		)
		(property "Value" "+3V3"
			(at 153.67 133.35 0)
			(effects
				(font
					(size 1.27 1.27)
				)
			)
		)
		(property "Footprint" ""
			(at 153.67 137.16 0)
			(effects
				(font
					(size 1.27 1.27)
				)
				(hide yes)
			)
		)
		(property "Datasheet" ""
			(at 153.67 137.16 0)
			(effects
				(font
					(size 1.27 1.27)
				)
				(hide yes)
			)
		)
		(property "Description" ""
			(at 153.67 137.16 0)
			(effects
				(font
					(size 1.27 1.27)
				)
				(hide yes)
			)
		)
		(pin "1"
		)
		(instances
			(project "oculink-to-pcie-adapter"
				(path ""
					(reference "#PWR0348")
					(unit 1)
				)
			)
		)
	)
	(symbol
		(lib_id "antmicroClockTimingRealTimeClocks:DSC557-0343FI1")
		(at 163.83 138.43 0)
		(unit 1)
		(exclude_from_sim no)
		(in_bom yes)
		(on_board yes)
		(dnp no)
		(fields_autoplaced yes)
		(property "Reference" "U7"
			(at 177.165 128.27 0)
			(effects
				(font
					(size 1.27 1.27)
					(thickness 0.15)
				)
			)
		)
		(property "Value" "DSC557-0343FI1"
			(at 209.55 148.59 0)
			(effects
				(font
					(size 1.27 1.27)
					(thickness 0.15)
				)
				(justify left bottom)
				(hide yes)
			)
		)
		(property "Footprint" "antmicro-footprints:VQFN-14-1EP_3.2x2.5mm_P0.5mm_Layout4x3"
			(at 209.55 153.67 0)
			(effects
				(font
					(size 1.27 1.27)
					(thickness 0.15)
				)
				(justify left bottom)
				(hide yes)
			)
		)
		(property "Datasheet" "https://ww1.microchip.com/downloads/aemDocuments/documents/TCG/ProductDocuments/DataSheets/DSC557-03-04-05-Multiple-Output-MEMS-PCIe-Gen1-2-3-4-Clock-Generators-DS20006691.pdf"
			(at 209.55 158.75 0)
			(effects
				(font
					(size 1.27 1.27)
					(thickness 0.15)
				)
				(justify left bottom)
				(hide yes)
			)
		)
		(property "Description" "Two output PCIe Clock Generator"
			(at 225.552 167.894 0)
			(effects
				(font
					(size 1.27 1.27)
				)
				(hide yes)
			)
		)
		(property "Manufacturer" "Microchip Technology"
			(at 209.55 161.29 0)
			(effects
				(font
					(size 1.27 1.27)
					(thickness 0.15)
				)
				(justify left bottom)
				(hide yes)
			)
		)
		(property "MPN" "DSC557-0343FI1"
			(at 177.165 130.81 0)
			(effects
				(font
					(size 1.27 1.27)
					(thickness 0.15)
				)
			)
		)
		(property "Val" "100 MHz"
			(at 177.165 133.35 0)
			(effects
				(font
					(size 1.27 1.27)
				)
			)
		)
		(property "Author" "Antmicro"
			(at 209.55 163.83 0)
			(effects
				(font
					(size 1.27 1.27)
					(thickness 0.15)
				)
				(justify left bottom)
				(hide yes)
			)
		)
		(property "License" "Apache-2.0"
			(at 209.55 166.37 0)
			(effects
				(font
					(size 1.27 1.27)
					(thickness 0.15)
				)
				(justify left bottom)
				(hide yes)
			)
		)
		(pin "1"
		)
		(pin "9"
		)
		(pin "8"
		)
		(pin "5"
		)
		(pin "10"
		)
		(pin "11"
		)
		(pin "6"
		)
		(pin "3"
		)
		(pin "14"
		)
		(pin "15"
		)
		(pin "12"
		)
		(pin "13"
		)
		(pin "4"
		)
		(pin "2"
		)
		(pin "7"
		)
		(instances
			(project ""
				(path ""
					(reference "U7")
					(unit 1)
				)
			)
		)
	)
	(symbol
		(lib_id "antmicroResistors0402:R_22R_0402")
		(at 214.63 147.32 0)
		(unit 1)
		(exclude_from_sim no)
		(in_bom yes)
		(on_board yes)
		(dnp no)
		(property "Reference" "R55"
			(at 213.36 146.05 0)
			(effects
				(font
					(size 1.27 1.27)
					(thickness 0.15)
				)
			)
		)
		(property "Value" "R_22R_0402"
			(at 234.95 160.02 0)
			(effects
				(font
					(size 1.27 1.27)
					(thickness 0.15)
				)
				(justify left bottom)
				(hide yes)
			)
		)
		(property "Footprint" "antmicro-footprints:R_0402_1005Metric"
			(at 234.95 162.56 0)
			(effects
				(font
					(size 1.27 1.27)
					(thickness 0.15)
				)
				(justify left bottom)
				(hide yes)
			)
		)
		(property "Datasheet" "https://www.bourns.com/docs/product-datasheets/cr.pdf"
			(at 234.95 165.1 0)
			(effects
				(font
					(size 1.27 1.27)
					(thickness 0.15)
				)
				(justify left bottom)
				(hide yes)
			)
		)
		(property "Description" "SMD Chip Resistor, 22 ohm, ± 1%, 62.5 mW, 0402 [1005 Metric], Thick Film, General Purpose"
			(at 214.63 147.32 0)
			(effects
				(font
					(size 1.27 1.27)
				)
				(hide yes)
			)
		)
		(property "MPN" "CR0402-FX-22R0GLF"
			(at 234.95 167.64 0)
			(effects
				(font
					(size 1.27 1.27)
					(thickness 0.15)
				)
				(justify left bottom)
				(hide yes)
			)
		)
		(property "Manufacturer" "Bourns"
			(at 234.95 170.18 0)
			(effects
				(font
					(size 1.27 1.27)
					(thickness 0.15)
				)
				(justify left bottom)
				(hide yes)
			)
		)
		(property "License" "Apache-2.0"
			(at 234.95 172.72 0)
			(effects
				(font
					(size 1.27 1.27)
					(thickness 0.15)
				)
				(justify left bottom)
				(hide yes)
			)
		)
		(property "Author" "Antmicro"
			(at 234.95 175.26 0)
			(effects
				(font
					(size 1.27 1.27)
					(thickness 0.15)
				)
				(justify left bottom)
				(hide yes)
			)
		)
		(property "Val" "22R"
			(at 221.615 146.05 0)
			(effects
				(font
					(size 1.27 1.27)
					(thickness 0.15)
				)
			)
		)
		(property "Tolerance" "1%"
			(at 234.95 157.48 0)
			(effects
				(font
					(size 1.27 1.27)
				)
				(justify left bottom)
				(hide yes)
			)
		)
		(pin "1"
		)
		(pin "2"
		)
		(instances
			(project ""
				(path ""
					(reference "R55")
					(unit 1)
				)
			)
		)
	)
	(symbol
		(lib_id "antmicroCapacitors0402:C_100n_0402")
		(at 153.67 144.78 270)
		(mirror x)
		(unit 1)
		(exclude_from_sim no)
		(in_bom yes)
		(on_board yes)
		(dnp no)
		(property "Reference" "C42"
			(at 151.638 140.97 90)
			(effects
				(font
					(size 1.27 1.27)
					(thickness 0.15)
				)
				(justify right)
			)
		)
		(property "Value" "C_100n_0402"
			(at 143.51 124.46 0)
			(effects
				(font
					(size 1.27 1.27)
					(thickness 0.15)
				)
				(justify left bottom)
				(hide yes)
			)
		)
		(property "Footprint" "antmicro-footprints:C_0402_1005Metric"
			(at 140.97 124.46 0)
			(effects
				(font
					(size 1.27 1.27)
					(thickness 0.15)
				)
				(justify left bottom)
				(hide yes)
			)
		)
		(property "Datasheet" "https://www.murata.com/products/productdetail?partno=GRM155R61H104KE14%23"
			(at 138.43 124.46 0)
			(effects
				(font
					(size 1.27 1.27)
					(thickness 0.15)
				)
				(justify left bottom)
				(hide yes)
			)
		)
		(property "Description" "SMD Multilayer Ceramic Capacitor, 0.1 µF, 50 V, 0402 [1005 Metric], ± 10%, X5R, GRM Series"
			(at 153.67 144.78 0)
			(effects
				(font
					(size 1.27 1.27)
				)
				(hide yes)
			)
		)
		(property "MPN" "GRM155R61H104KE14D"
			(at 135.89 124.46 0)
			(effects
				(font
					(size 1.27 1.27)
					(thickness 0.15)
				)
				(justify left bottom)
				(hide yes)
			)
		)
		(property "Manufacturer" "Murata"
			(at 133.35 124.46 0)
			(effects
				(font
					(size 1.27 1.27)
					(thickness 0.15)
				)
				(justify left bottom)
				(hide yes)
			)
		)
		(property "License" "Apache-2.0"
			(at 130.81 124.46 0)
			(effects
				(font
					(size 1.27 1.27)
					(thickness 0.15)
				)
				(justify left bottom)
				(hide yes)
			)
		)
		(property "Author" "Antmicro"
			(at 128.27 124.46 0)
			(effects
				(font
					(size 1.27 1.27)
					(thickness 0.15)
				)
				(justify left bottom)
				(hide yes)
			)
		)
		(property "Val" "100n"
			(at 151.638 143.51 90)
			(effects
				(font
					(size 1.27 1.27)
					(thickness 0.15)
				)
				(justify right)
			)
		)
		(property "Voltage" "50V"
			(at 125.73 124.46 0)
			(effects
				(font
					(size 1.27 1.27)
				)
				(justify left bottom)
				(hide yes)
			)
		)
		(property "Dielectric" "X5R"
			(at 123.19 124.46 0)
			(effects
				(font
					(size 1.27 1.27)
				)
				(justify left bottom)
				(hide yes)
			)
		)
		(pin "1"
		)
		(pin "2"
		)
		(instances
			(project "oculink-to-pcie-adapter"
				(path ""
					(reference "C42")
					(unit 1)
				)
			)
		)
	)
	(symbol
		(lib_id "antmicroResistors0402:R_0R_0402")
		(at 243.84 147.32 0)
		(unit 1)
		(exclude_from_sim no)
		(in_bom yes)
		(on_board yes)
		(dnp no)
		(property "Reference" "R43"
			(at 242.062 146.05 0)
			(effects
				(font
					(size 1.27 1.27)
					(thickness 0.15)
				)
			)
		)
		(property "Value" "R_0R_0402"
			(at 264.16 160.02 0)
			(effects
				(font
					(size 1.27 1.27)
					(thickness 0.15)
				)
				(justify left bottom)
				(hide yes)
			)
		)
		(property "Footprint" "antmicro-footprints:R_0402_1005Metric"
			(at 264.16 162.56 0)
			(effects
				(font
					(size 1.27 1.27)
					(thickness 0.15)
				)
				(justify left bottom)
				(hide yes)
			)
		)
		(property "Datasheet" "https://industrial.panasonic.com/cdbs/www-data/pdf/RDA0000/AOA0000C301.pdf"
			(at 264.16 165.1 0)
			(effects
				(font
					(size 1.27 1.27)
					(thickness 0.15)
				)
				(justify left bottom)
				(hide yes)
			)
		)
		(property "Description" "SMD Chip Resistor, Jumper, 0 ohm, 100 mW, 0402 [1005 Metric], Thick Film, General Purpose"
			(at 243.84 147.32 0)
			(effects
				(font
					(size 1.27 1.27)
				)
				(hide yes)
			)
		)
		(property "MPN" "ERJ2GE0R00X"
			(at 264.16 167.64 0)
			(effects
				(font
					(size 1.27 1.27)
					(thickness 0.15)
				)
				(justify left bottom)
				(hide yes)
			)
		)
		(property "Manufacturer" "Panasonic"
			(at 264.16 170.18 0)
			(effects
				(font
					(size 1.27 1.27)
					(thickness 0.15)
				)
				(justify left bottom)
				(hide yes)
			)
		)
		(property "License" "Apache-2.0"
			(at 264.16 172.72 0)
			(effects
				(font
					(size 1.27 1.27)
					(thickness 0.15)
				)
				(justify left bottom)
				(hide yes)
			)
		)
		(property "Author" "Antmicro"
			(at 264.16 175.26 0)
			(effects
				(font
					(size 1.27 1.27)
					(thickness 0.15)
				)
				(justify left bottom)
				(hide yes)
			)
		)
		(property "Val" "0R"
			(at 249.936 146.05 0)
			(effects
				(font
					(size 1.27 1.27)
					(thickness 0.15)
				)
			)
		)
		(property "Tolerance" "~"
			(at 264.16 157.48 0)
			(effects
				(font
					(size 1.27 1.27)
				)
				(justify left bottom)
				(hide yes)
			)
		)
		(property "Current" "1A"
			(at 264.16 177.8 0)
			(effects
				(font
					(size 1.27 1.27)
					(thickness 0.15)
				)
				(justify left bottom)
				(hide yes)
			)
		)
		(pin "1"
		)
		(pin "2"
		)
		(instances
			(project "oculink-to-pcie-adapter"
				(path ""
					(reference "R43")
					(unit 1)
				)
			)
		)
	)
	(symbol
		(lib_id "antmicropower:GND")
		(at 153.67 144.78 0)
		(unit 1)
		(exclude_from_sim no)
		(in_bom yes)
		(on_board yes)
		(dnp no)
		(property "Reference" "#PWR0103"
			(at 162.56 147.32 0)
			(effects
				(font
					(size 1.27 1.27)
					(thickness 0.15)
				)
				(justify left bottom)
				(hide yes)
			)
		)
		(property "Value" "GND"
			(at 153.67 148.59 0)
			(effects
				(font
					(size 1.27 1.27)
					(thickness 0.15)
				)
			)
		)
		(property "Footprint" ""
			(at 162.56 152.4 0)
			(effects
				(font
					(size 1.27 1.27)
					(thickness 0.15)
				)
				(justify left bottom)
				(hide yes)
			)
		)
		(property "Datasheet" ""
			(at 162.56 157.48 0)
			(effects
				(font
					(size 1.27 1.27)
					(thickness 0.15)
				)
				(justify left bottom)
				(hide yes)
			)
		)
		(property "Description" ""
			(at 153.67 144.78 0)
			(effects
				(font
					(size 1.27 1.27)
				)
				(hide yes)
			)
		)
		(property "Author" "Antmicro"
			(at 162.56 152.4 0)
			(effects
				(font
					(size 1.27 1.27)
					(thickness 0.15)
				)
				(justify left bottom)
				(hide yes)
			)
		)
		(property "License" "Apache-2.0"
			(at 162.56 154.94 0)
			(effects
				(font
					(size 1.27 1.27)
					(thickness 0.15)
				)
				(justify left bottom)
				(hide yes)
			)
		)
		(pin "1"
		)
		(instances
			(project "oculink-to-pcie-adapter"
				(path ""
					(reference "#PWR0103")
					(unit 1)
				)
			)
		)
	)
	(symbol
		(lib_id "antmicroResistors0402:R_50R_0402")
		(at 224.79 160.02 270)
		(mirror x)
		(unit 1)
		(exclude_from_sim no)
		(in_bom yes)
		(on_board yes)
		(dnp yes)
		(property "Reference" "R58"
			(at 229.87 156.21 90)
			(effects
				(font
					(size 1.27 1.27)
					(thickness 0.15)
				)
				(justify right)
			)
		)
		(property "Value" "R_50R_0402"
			(at 212.09 139.7 0)
			(effects
				(font
					(size 1.27 1.27)
					(thickness 0.15)
				)
				(justify left bottom)
				(hide yes)
			)
		)
		(property "Footprint" "antmicro-footprints:R_0402_1005Metric"
			(at 209.55 139.7 0)
			(effects
				(font
					(size 1.27 1.27)
					(thickness 0.15)
				)
				(justify left bottom)
				(hide yes)
			)
		)
		(property "Datasheet" "https://www.bourns.com/docs/product-datasheets/cr.pdf"
			(at 207.01 139.7 0)
			(effects
				(font
					(size 1.27 1.27)
					(thickness 0.15)
				)
				(justify left bottom)
				(hide yes)
			)
		)
		(property "Description" "SMD Chip Resistor"
			(at 224.79 160.02 0)
			(effects
				(font
					(size 1.27 1.27)
				)
				(hide yes)
			)
		)
		(property "MPN" "CR0402-FX-50R0GLF"
			(at 204.47 139.7 0)
			(effects
				(font
					(size 1.27 1.27)
					(thickness 0.15)
				)
				(justify left bottom)
				(hide yes)
			)
		)
		(property "Manufacturer" "Bourns"
			(at 201.93 139.7 0)
			(effects
				(font
					(size 1.27 1.27)
					(thickness 0.15)
				)
				(justify left bottom)
				(hide yes)
			)
		)
		(property "License" "Apache-2.0"
			(at 199.39 139.7 0)
			(effects
				(font
					(size 1.27 1.27)
					(thickness 0.15)
				)
				(justify left bottom)
				(hide yes)
			)
		)
		(property "Author" "Antmicro"
			(at 196.85 139.7 0)
			(effects
				(font
					(size 1.27 1.27)
					(thickness 0.15)
				)
				(justify left bottom)
				(hide yes)
			)
		)
		(property "Val" "50R"
			(at 229.87 158.75 90)
			(effects
				(font
					(size 1.27 1.27)
					(thickness 0.15)
				)
				(justify right)
			)
		)
		(property "Tolerance" "1%"
			(at 214.63 139.7 0)
			(effects
				(font
					(size 1.27 1.27)
				)
				(justify left bottom)
				(hide yes)
			)
		)
		(pin "1"
		)
		(pin "2"
		)
		(instances
			(project "oculink-to-pcie-adapter"
				(path ""
					(reference "R58")
					(unit 1)
				)
			)
		)
	)
	(symbol
		(lib_id "antmicropower:GND")
		(at 224.79 161.29 0)
		(mirror y)
		(unit 1)
		(exclude_from_sim no)
		(in_bom yes)
		(on_board yes)
		(dnp no)
		(property "Reference" "#PWR0106"
			(at 215.9 163.83 0)
			(effects
				(font
					(size 1.27 1.27)
					(thickness 0.15)
				)
				(justify left bottom)
				(hide yes)
			)
		)
		(property "Value" "GND"
			(at 224.79 165.1 0)
			(effects
				(font
					(size 1.27 1.27)
					(thickness 0.15)
				)
			)
		)
		(property "Footprint" ""
			(at 215.9 168.91 0)
			(effects
				(font
					(size 1.27 1.27)
					(thickness 0.15)
				)
				(justify left bottom)
				(hide yes)
			)
		)
		(property "Datasheet" ""
			(at 215.9 173.99 0)
			(effects
				(font
					(size 1.27 1.27)
					(thickness 0.15)
				)
				(justify left bottom)
				(hide yes)
			)
		)
		(property "Description" ""
			(at 224.79 161.29 0)
			(effects
				(font
					(size 1.27 1.27)
				)
				(hide yes)
			)
		)
		(property "Author" "Antmicro"
			(at 215.9 168.91 0)
			(effects
				(font
					(size 1.27 1.27)
					(thickness 0.15)
				)
				(justify left bottom)
				(hide yes)
			)
		)
		(property "License" "Apache-2.0"
			(at 215.9 171.45 0)
			(effects
				(font
					(size 1.27 1.27)
					(thickness 0.15)
				)
				(justify left bottom)
				(hide yes)
			)
		)
		(pin "1"
		)
		(instances
			(project "oculink-to-pcie-adapter"
				(path ""
					(reference "#PWR0106")
					(unit 1)
				)
			)
		)
	)
	(symbol
		(lib_id "antmicroResistors0402:R_50R_0402")
		(at 231.14 160.02 270)
		(mirror x)
		(unit 1)
		(exclude_from_sim no)
		(in_bom yes)
		(on_board yes)
		(dnp yes)
		(property "Reference" "R57"
			(at 236.22 156.21 90)
			(effects
				(font
					(size 1.27 1.27)
					(thickness 0.15)
				)
				(justify right)
			)
		)
		(property "Value" "R_50R_0402"
			(at 218.44 139.7 0)
			(effects
				(font
					(size 1.27 1.27)
					(thickness 0.15)
				)
				(justify left bottom)
				(hide yes)
			)
		)
		(property "Footprint" "antmicro-footprints:R_0402_1005Metric"
			(at 215.9 139.7 0)
			(effects
				(font
					(size 1.27 1.27)
					(thickness 0.15)
				)
				(justify left bottom)
				(hide yes)
			)
		)
		(property "Datasheet" "https://www.bourns.com/docs/product-datasheets/cr.pdf"
			(at 213.36 139.7 0)
			(effects
				(font
					(size 1.27 1.27)
					(thickness 0.15)
				)
				(justify left bottom)
				(hide yes)
			)
		)
		(property "Description" "SMD Chip Resistor"
			(at 231.14 160.02 0)
			(effects
				(font
					(size 1.27 1.27)
				)
				(hide yes)
			)
		)
		(property "MPN" "CR0402-FX-50R0GLF"
			(at 210.82 139.7 0)
			(effects
				(font
					(size 1.27 1.27)
					(thickness 0.15)
				)
				(justify left bottom)
				(hide yes)
			)
		)
		(property "Manufacturer" "Bourns"
			(at 208.28 139.7 0)
			(effects
				(font
					(size 1.27 1.27)
					(thickness 0.15)
				)
				(justify left bottom)
				(hide yes)
			)
		)
		(property "License" "Apache-2.0"
			(at 205.74 139.7 0)
			(effects
				(font
					(size 1.27 1.27)
					(thickness 0.15)
				)
				(justify left bottom)
				(hide yes)
			)
		)
		(property "Author" "Antmicro"
			(at 203.2 139.7 0)
			(effects
				(font
					(size 1.27 1.27)
					(thickness 0.15)
				)
				(justify left bottom)
				(hide yes)
			)
		)
		(property "Val" "50R"
			(at 236.22 158.75 90)
			(effects
				(font
					(size 1.27 1.27)
					(thickness 0.15)
				)
				(justify right)
			)
		)
		(property "Tolerance" "1%"
			(at 220.98 139.7 0)
			(effects
				(font
					(size 1.27 1.27)
				)
				(justify left bottom)
				(hide yes)
			)
		)
		(pin "1"
		)
		(pin "2"
		)
		(instances
			(project "oculink-to-pcie-adapter"
				(path ""
					(reference "R57")
					(unit 1)
				)
			)
		)
	)
	(symbol
		(lib_id "antmicropower:GND")
		(at 231.14 161.29 0)
		(mirror y)
		(unit 1)
		(exclude_from_sim no)
		(in_bom yes)
		(on_board yes)
		(dnp no)
		(property "Reference" "#PWR0105"
			(at 222.25 163.83 0)
			(effects
				(font
					(size 1.27 1.27)
					(thickness 0.15)
				)
				(justify left bottom)
				(hide yes)
			)
		)
		(property "Value" "GND"
			(at 231.14 165.1 0)
			(effects
				(font
					(size 1.27 1.27)
					(thickness 0.15)
				)
			)
		)
		(property "Footprint" ""
			(at 222.25 168.91 0)
			(effects
				(font
					(size 1.27 1.27)
					(thickness 0.15)
				)
				(justify left bottom)
				(hide yes)
			)
		)
		(property "Datasheet" ""
			(at 222.25 173.99 0)
			(effects
				(font
					(size 1.27 1.27)
					(thickness 0.15)
				)
				(justify left bottom)
				(hide yes)
			)
		)
		(property "Description" ""
			(at 231.14 161.29 0)
			(effects
				(font
					(size 1.27 1.27)
				)
				(hide yes)
			)
		)
		(property "Author" "Antmicro"
			(at 222.25 168.91 0)
			(effects
				(font
					(size 1.27 1.27)
					(thickness 0.15)
				)
				(justify left bottom)
				(hide yes)
			)
		)
		(property "License" "Apache-2.0"
			(at 222.25 171.45 0)
			(effects
				(font
					(size 1.27 1.27)
					(thickness 0.15)
				)
				(justify left bottom)
				(hide yes)
			)
		)
		(pin "1"
		)
		(instances
			(project "oculink-to-pcie-adapter"
				(path ""
					(reference "#PWR0105")
					(unit 1)
				)
			)
		)
	)
	(symbol
		(lib_id "antmicroResistors0402:R_22R_0402")
		(at 214.63 149.86 0)
		(unit 1)
		(exclude_from_sim no)
		(in_bom yes)
		(on_board yes)
		(dnp no)
		(property "Reference" "R56"
			(at 213.36 148.59 0)
			(effects
				(font
					(size 1.27 1.27)
					(thickness 0.15)
				)
			)
		)
		(property "Value" "R_22R_0402"
			(at 234.95 162.56 0)
			(effects
				(font
					(size 1.27 1.27)
					(thickness 0.15)
				)
				(justify left bottom)
				(hide yes)
			)
		)
		(property "Footprint" "antmicro-footprints:R_0402_1005Metric"
			(at 234.95 165.1 0)
			(effects
				(font
					(size 1.27 1.27)
					(thickness 0.15)
				)
				(justify left bottom)
				(hide yes)
			)
		)
		(property "Datasheet" "https://www.bourns.com/docs/product-datasheets/cr.pdf"
			(at 234.95 167.64 0)
			(effects
				(font
					(size 1.27 1.27)
					(thickness 0.15)
				)
				(justify left bottom)
				(hide yes)
			)
		)
		(property "Description" "SMD Chip Resistor, 22 ohm, ± 1%, 62.5 mW, 0402 [1005 Metric], Thick Film, General Purpose"
			(at 214.63 149.86 0)
			(effects
				(font
					(size 1.27 1.27)
				)
				(hide yes)
			)
		)
		(property "MPN" "CR0402-FX-22R0GLF"
			(at 234.95 170.18 0)
			(effects
				(font
					(size 1.27 1.27)
					(thickness 0.15)
				)
				(justify left bottom)
				(hide yes)
			)
		)
		(property "Manufacturer" "Bourns"
			(at 234.95 172.72 0)
			(effects
				(font
					(size 1.27 1.27)
					(thickness 0.15)
				)
				(justify left bottom)
				(hide yes)
			)
		)
		(property "License" "Apache-2.0"
			(at 234.95 175.26 0)
			(effects
				(font
					(size 1.27 1.27)
					(thickness 0.15)
				)
				(justify left bottom)
				(hide yes)
			)
		)
		(property "Author" "Antmicro"
			(at 234.95 177.8 0)
			(effects
				(font
					(size 1.27 1.27)
					(thickness 0.15)
				)
				(justify left bottom)
				(hide yes)
			)
		)
		(property "Val" "22R"
			(at 221.615 148.59 0)
			(effects
				(font
					(size 1.27 1.27)
					(thickness 0.15)
				)
			)
		)
		(property "Tolerance" "1%"
			(at 234.95 160.02 0)
			(effects
				(font
					(size 1.27 1.27)
				)
				(justify left bottom)
				(hide yes)
			)
		)
		(pin "1"
		)
		(pin "2"
		)
		(instances
			(project "oculink-to-pcie-adapter"
				(path ""
					(reference "R56")
					(unit 1)
				)
			)
		)
	)
)
